(kicad_pcb
	(version 20260206)
	(generator "pcbnew")
	(generator_version "10.0")
	(general
		(thickness 1.6)
		(legacy_teardrops no)
	)
	(paper "A4")
	(title_block
		(title "Wiwynn_Tioga_Pass_MB.brd")
		(comment 1 "Tioga Pass / footprint 190 of 4770 (U2D1), pads 2406-2517 of 3647")
	)
	(layers
		(0 "F.Cu" signal "TOP")
		(4 "In1.Cu" signal "L2GND")
		(6 "In2.Cu" signal "L3")
		(8 "In3.Cu" signal "L4GND")
		(10 "In4.Cu" signal "L5")
		(12 "In5.Cu" signal "L6GND")
		(14 "In6.Cu" signal "L7VCC")
		(16 "In7.Cu" signal "L8VCC")
		(18 "In8.Cu" signal "L9GND")
		(20 "In9.Cu" signal "L10")
		(22 "In10.Cu" signal "L11GND")
		(24 "In11.Cu" signal "L12")
		(26 "In12.Cu" signal "L13GND")
		(2 "B.Cu" signal "BOTTOM")
		(9 "F.Adhes" user "F.Adhesive")
		(11 "B.Adhes" user "B.Adhesive")
		(13 "F.Paste" user "Package Geometry/Pastemask Top")
		(15 "B.Paste" user "Package Geometry/Pastemask Bottom")
		(5 "F.SilkS" user "Ref Des/Silkscreen Top")
		(7 "B.SilkS" user "Ref Des/Silkscreen Bottom")
		(1 "F.Mask" user "Board Geometry/Soldermask Top")
		(3 "B.Mask" user "Board Geometry/Soldermask Bottom")
		(17 "Dwgs.User" user "User.Drawings")
		(19 "Cmts.User" user "User.Comments")
		(21 "Eco1.User" user "User.Eco1")
		(23 "Eco2.User" user "User.Eco2")
		(25 "Edge.Cuts" user "Board Geometry/Outline")
		(27 "Margin" user)
		(31 "F.CrtYd" user "Package Geometry/Place Bound Top")
		(29 "B.CrtYd" user "Package Geometry/Place Bound Bottom")
		(35 "F.Fab" user "Ref Des/Assembly Top")
		(33 "B.Fab" user "Ref Des/Assembly Bottom")
	)
	(footprint ""
		(layer "F.Cu")
		(at 104.99979 -76.550012 180)
		(property "Reference" "U2D1"
			(at 25.19299 30.484318 0)
			(unlocked yes)
			(layer "F.SilkS")
			(effects
				(font
					(size 0.7874 0.5842)
					(thickness 0.1524)
				)
			)
		)
		(property "Value" ""
			(at 0 0 180)
			(layer "F.Fab")
			(effects
				(font
					(size 1.27 1.27)
				)
			)
		)
		(duplicate_pad_numbers_are_jumpers no)
		(pad "DM13" smd circle
			(at -26.948384 19.968972)
			(size 0.4318 0.4318)
			(layers "F.Cu" "F.Mask" "F.Paste")
			(net "P3E_CPU1_PE3_MP_RXP<6>")
		)
		(pad "DM15" smd circle
			(at -25.231598 19.968972)
			(size 0.4318 0.4318)
			(layers "F.Cu" "F.Mask" "F.Paste")
			(net "GND")
		)
		(pad "DM17" smd circle
			(at -23.514558 19.968972)
			(size 0.4318 0.4318)
			(layers "F.Cu" "F.Mask" "F.Paste")
			(net "PVCCIO_CPU1")
		)
		(pad "DM19" smd circle
			(at -21.797518 19.968972)
			(size 0.4318 0.4318)
			(layers "F.Cu" "F.Mask" "F.Paste")
			(net "GND")
		)
		(pad "DM21" smd circle
			(at -20.080478 19.968972)
			(size 0.4318 0.4318)
			(layers "F.Cu" "F.Mask" "F.Paste")
			(net "TP_CPU1_UPI2_RSVD_CC10")
		)
		(pad "DM23" smd circle
			(at -18.363438 19.968972)
			(size 0.4318 0.4318)
			(layers "F.Cu" "F.Mask" "F.Paste")
			(net "M_K_DQS_DN<16>")
		)
		(pad "DM25" smd circle
			(at -16.646398 19.968972)
			(size 0.4318 0.4318)
			(layers "F.Cu" "F.Mask" "F.Paste")
			(net "GND")
		)
		(pad "DM27" smd circle
			(at -14.929612 19.968972)
			(size 0.4318 0.4318)
			(layers "F.Cu" "F.Mask" "F.Paste")
			(net "GND")
		)
		(pad "DM29" smd circle
			(at -13.212572 19.968972)
			(size 0.4318 0.4318)
			(layers "F.Cu" "F.Mask" "F.Paste")
			(net "M_K_DQS_DN<15>")
		)
		(pad "DM31" smd circle
			(at -11.495532 19.968972)
			(size 0.4318 0.4318)
			(layers "F.Cu" "F.Mask" "F.Paste")
			(net "GND")
		)
		(pad "DM33" smd circle
			(at -9.778492 19.968972)
			(size 0.4318 0.4318)
			(layers "F.Cu" "F.Mask" "F.Paste")
			(net "GND")
		)
		(pad "DM35" smd circle
			(at -8.061452 19.968972)
			(size 0.4318 0.4318)
			(layers "F.Cu" "F.Mask" "F.Paste")
			(net "M_K_DQS_DP<14>")
		)
		(pad "DM37" smd circle
			(at -6.344412 19.968972)
			(size 0.4318 0.4318)
			(layers "F.Cu" "F.Mask" "F.Paste")
			(net "GND")
		)
		(pad "DM39" smd circle
			(at -4.627626 19.968972)
			(size 0.4318 0.4318)
			(layers "F.Cu" "F.Mask" "F.Paste")
			(net "GND")
		)
		(pad "DM41" smd circle
			(at -2.910586 19.968972)
			(size 0.4318 0.4318)
			(layers "F.Cu" "F.Mask" "F.Paste")
			(net "M_L_DQS_DP<13>")
		)
		(pad "DM45" smd circle
			(at 2.052066 18.168874)
			(size 0.4318 0.4318)
			(layers "F.Cu" "F.Mask" "F.Paste")
			(net "M_M_CS_N<6>")
		)
		(pad "DM47" smd circle
			(at 3.769106 18.168874)
			(size 0.4318 0.4318)
			(layers "F.Cu" "F.Mask" "F.Paste")
			(net "M_L_ODT<3>")
		)
		(pad "DM49" smd circle
			(at 5.485892 18.168874)
			(size 0.4318 0.4318)
			(layers "F.Cu" "F.Mask" "F.Paste")
			(net "M_L_CS_N<5>")
		)
		(pad "DM51" smd circle
			(at 7.202932 18.168874)
			(size 0.4318 0.4318)
			(layers "F.Cu" "F.Mask" "F.Paste")
			(net "M_L_MA<14>")
		)
		(pad "DM53" smd circle
			(at 8.919972 18.168874)
			(size 0.4318 0.4318)
			(layers "F.Cu" "F.Mask" "F.Paste")
			(net "M_L_BA<0>")
		)
		(pad "DM55" smd circle
			(at 10.637012 18.168874)
			(size 0.4318 0.4318)
			(layers "F.Cu" "F.Mask" "F.Paste")
			(net "M_L_CLK_DN<0>")
		)
		(pad "DM57" smd circle
			(at 12.354052 18.168874)
			(size 0.4318 0.4318)
			(layers "F.Cu" "F.Mask" "F.Paste")
			(net "M_L_CLK_DN<2>")
		)
		(pad "DM59" smd circle
			(at 14.071092 18.168874)
			(size 0.4318 0.4318)
			(layers "F.Cu" "F.Mask" "F.Paste")
			(net "M_L_MA<6>")
		)
		(pad "DM61" smd circle
			(at 15.787878 18.168874)
			(size 0.4318 0.4318)
			(layers "F.Cu" "F.Mask" "F.Paste")
			(net "M_L_BG<1>")
		)
		(pad "DM63" smd circle
			(at 17.504918 18.168874)
			(size 0.4318 0.4318)
			(layers "F.Cu" "F.Mask" "F.Paste")
			(net "M_L_CKE<0>")
		)
		(pad "DM65" smd circle
			(at 19.221958 18.168874)
			(size 0.4318 0.4318)
			(layers "F.Cu" "F.Mask" "F.Paste")
			(net "GND")
		)
		(pad "DM67" smd circle
			(at 20.938998 18.168874)
			(size 0.4318 0.4318)
			(layers "F.Cu" "F.Mask" "F.Paste")
			(net "TP_CPU1_RSVD_33")
		)
		(pad "DM69" smd circle
			(at 22.656038 18.168874)
			(size 0.4318 0.4318)
			(layers "F.Cu" "F.Mask" "F.Paste")
			(net "M_M_DQ<18>")
		)
		(pad "DM71" smd circle
			(at 24.373078 18.168874)
			(size 0.4318 0.4318)
			(layers "F.Cu" "F.Mask" "F.Paste")
			(net "M_M_DQ<23>")
		)
		(pad "DM73" smd circle
			(at 26.090118 18.168874)
			(size 0.4318 0.4318)
			(layers "F.Cu" "F.Mask" "F.Paste")
			(net "GND")
		)
		(pad "DM75" smd circle
			(at 27.806904 18.168874)
			(size 0.4318 0.4318)
			(layers "F.Cu" "F.Mask" "F.Paste")
			(net "M_K_DQS_DP<12>")
		)
		(pad "DM77" smd circle
			(at 29.523944 18.168874)
			(size 0.4318 0.4318)
			(layers "F.Cu" "F.Mask" "F.Paste")
			(net "GND")
		)
		(pad "DM79" smd circle
			(at 31.240984 18.168874)
			(size 0.4318 0.4318)
			(layers "F.Cu" "F.Mask" "F.Paste")
			(net "M_K_DQ<16>")
		)
		(pad "DM81" smd circle
			(at 32.958024 18.168874)
			(size 0.4318 0.4318)
			(layers "F.Cu" "F.Mask" "F.Paste")
			(net "M_K_DQS_DP<2>")
		)
		(pad "DM83" smd circle
			(at 34.675064 18.168874)
			(size 0.4318 0.4318)
			(layers "F.Cu" "F.Mask" "F.Paste")
			(net "GND")
		)
		(pad "DM85" smd custom
			(at 36.392104 18.168874 270)
			(size 0.10795 0.10795)
			(layers "F.Cu" "F.Mask" "F.Paste")
			(net "M_K_DQS_DN<10>")
			(options
				(clearance outline)
				(anchor circle)
			)
			(primitives
				(gr_poly
					(pts
						(arc
							(start 0.2159 -0.0381)
							(mid 0 -0.254)
							(end -0.2159 -0.0381)
						)
						(arc
							(start -0.2159 0.0381)
							(mid 0 0.254)
							(end 0.2159 0.0381)
						)
					)
					(width 0)
					(fill yes)
				)
			)
		)
		(pad "DN2" smd custom
			(at -36.392104 20.464526 90)
			(size 0.10795 0.10795)
			(layers "F.Cu" "F.Mask" "F.Paste")
			(net "GND")
			(options
				(clearance outline)
				(anchor circle)
			)
			(primitives
				(gr_poly
					(pts
						(arc
							(start 0.2159 -0.0381)
							(mid 0 -0.254)
							(end -0.2159 -0.0381)
						)
						(arc
							(start -0.2159 0.0381)
							(mid 0 0.254)
							(end 0.2159 0.0381)
						)
					)
					(width 0)
					(fill yes)
				)
			)
		)
		(pad "DN4" smd circle
			(at -34.675064 20.464526)
			(size 0.4318 0.4318)
			(layers "F.Cu" "F.Mask" "F.Paste")
			(net "TP_P3E_CPU1_PE1_MP_TXN<7>")
		)
		(pad "DN6" smd circle
			(at -32.958024 20.464526)
			(size 0.4318 0.4318)
			(layers "F.Cu" "F.Mask" "F.Paste")
			(net "P3E_CPU1_PE3_MP_TXP<8>")
		)
		(pad "DN8" smd circle
			(at -31.240984 20.464526)
			(size 0.4318 0.4318)
			(layers "F.Cu" "F.Mask" "F.Paste")
			(net "PVCCIO_CPU1")
		)
		(pad "DN10" smd circle
			(at -29.523944 20.464526)
			(size 0.4318 0.4318)
			(layers "F.Cu" "F.Mask" "F.Paste")
			(net "TP_P3E_CPU1_PE1_RSR3_RXP<9>")
		)
		(pad "DN12" smd circle
			(at -27.806904 20.464526)
			(size 0.4318 0.4318)
			(layers "F.Cu" "F.Mask" "F.Paste")
			(net "GND")
		)
		(pad "DN14" smd circle
			(at -26.090118 20.464526)
			(size 0.4318 0.4318)
			(layers "F.Cu" "F.Mask" "F.Paste")
			(net "P3E_CPU1_PE3_MP_RXN<6>")
		)
		(pad "DN16" smd circle
			(at -24.373078 20.464526)
			(size 0.4318 0.4318)
			(layers "F.Cu" "F.Mask" "F.Paste")
			(net "P3E_CPU1_PE3_MP_RXP<4>")
		)
		(pad "DN18" smd circle
			(at -22.656038 20.464526)
			(size 0.4318 0.4318)
			(layers "F.Cu" "F.Mask" "F.Paste")
			(net "GND")
		)
		(pad "DN20" smd circle
			(at -20.938998 20.464526)
			(size 0.4318 0.4318)
			(layers "F.Cu" "F.Mask" "F.Paste")
			(net "TP_CPU1_UPI2_RSVD_CB11")
		)
		(pad "DN22" smd circle
			(at -19.221958 20.464526)
			(size 0.4318 0.4318)
			(layers "F.Cu" "F.Mask" "F.Paste")
			(net "GND")
		)
		(pad "DN24" smd circle
			(at -17.504918 20.464526)
			(size 0.4318 0.4318)
			(layers "F.Cu" "F.Mask" "F.Paste")
			(net "M_K_DQ<56>")
		)
		(pad "DN26" smd circle
			(at -15.787878 20.464526)
			(size 0.4318 0.4318)
			(layers "F.Cu" "F.Mask" "F.Paste")
			(net "GND")
		)
		(pad "DN28" smd circle
			(at -14.071092 20.464526)
			(size 0.4318 0.4318)
			(layers "F.Cu" "F.Mask" "F.Paste")
			(net "M_K_DQ<54>")
		)
		(pad "DN30" smd circle
			(at -12.354052 20.464526)
			(size 0.4318 0.4318)
			(layers "F.Cu" "F.Mask" "F.Paste")
			(net "M_K_DQ<48>")
		)
		(pad "DN32" smd circle
			(at -10.637012 20.464526)
			(size 0.4318 0.4318)
			(layers "F.Cu" "F.Mask" "F.Paste")
			(net "GND")
		)
		(pad "DN34" smd circle
			(at -8.919972 20.464526)
			(size 0.4318 0.4318)
			(layers "F.Cu" "F.Mask" "F.Paste")
			(net "M_K_DQ<46>")
		)
		(pad "DN36" smd circle
			(at -7.202932 20.464526)
			(size 0.4318 0.4318)
			(layers "F.Cu" "F.Mask" "F.Paste")
			(net "M_K_DQ<40>")
		)
		(pad "DN38" smd circle
			(at -5.485892 20.464526)
			(size 0.4318 0.4318)
			(layers "F.Cu" "F.Mask" "F.Paste")
			(net "GND")
		)
		(pad "DN40" smd circle
			(at -3.769106 20.464526)
			(size 0.4318 0.4318)
			(layers "F.Cu" "F.Mask" "F.Paste")
			(net "M_L_DQ<38>")
		)
		(pad "DN42" smd circle
			(at -2.052066 20.464526)
			(size 0.4318 0.4318)
			(layers "F.Cu" "F.Mask" "F.Paste")
			(net "M_L_DQ<37>")
		)
		(pad "DN44" smd circle
			(at 1.193546 18.664428)
			(size 0.508 0.508)
			(layers "F.Cu" "F.Mask" "F.Paste")
			(net "GND")
		)
		(pad "DN46" smd circle
			(at 2.910586 18.664428)
			(size 0.4318 0.4318)
			(layers "F.Cu" "F.Mask" "F.Paste")
			(net "M_L_CS_N<7>")
		)
		(pad "DN48" smd circle
			(at 4.627626 18.664428)
			(size 0.4318 0.4318)
			(layers "F.Cu" "F.Mask" "F.Paste")
			(net "M_L_ODT<1>")
		)
		(pad "DN50" smd circle
			(at 6.344412 18.664428)
			(size 0.4318 0.4318)
			(layers "F.Cu" "F.Mask" "F.Paste")
			(net "M_L_CS_N<1>")
		)
		(pad "DN52" smd circle
			(at 8.061452 18.664428)
			(size 0.4318 0.4318)
			(layers "F.Cu" "F.Mask" "F.Paste")
			(net "M_L_MA<16>")
		)
		(pad "DN54" smd circle
			(at 9.778492 18.664428)
			(size 0.4318 0.4318)
			(layers "F.Cu" "F.Mask" "F.Paste")
			(net "M_L_CLK_DP<0>")
		)
		(pad "DN56" smd circle
			(at 11.495532 18.664428)
			(size 0.4318 0.4318)
			(layers "F.Cu" "F.Mask" "F.Paste")
			(net "M_L_CLK_DP<2>")
		)
		(pad "DN58" smd circle
			(at 13.212572 18.664428)
			(size 0.4318 0.4318)
			(layers "F.Cu" "F.Mask" "F.Paste")
			(net "M_L_MA<5>")
		)
		(pad "DN60" smd circle
			(at 14.929612 18.664428)
			(size 0.4318 0.4318)
			(layers "F.Cu" "F.Mask" "F.Paste")
			(net "M_L_MA<12>")
		)
		(pad "DN62" smd circle
			(at 16.646398 18.664428)
			(size 0.4318 0.4318)
			(layers "F.Cu" "F.Mask" "F.Paste")
			(net "TP_CPU1_RSVD_32")
		)
		(pad "DN64" smd circle
			(at 18.363438 18.664428)
			(size 0.4318 0.4318)
			(layers "F.Cu" "F.Mask" "F.Paste")
			(net "M_L_CKE<1>")
		)
		(pad "DN66" smd circle
			(at 20.080478 18.664428)
			(size 0.4318 0.4318)
			(layers "F.Cu" "F.Mask" "F.Paste")
			(net "TP_CPU1_RSVD_31")
		)
		(pad "DN68" smd circle
			(at 21.797518 18.664428)
			(size 0.4318 0.4318)
			(layers "F.Cu" "F.Mask" "F.Paste")
			(net "GND")
		)
		(pad "DN70" smd circle
			(at 23.514558 18.664428)
			(size 0.4318 0.4318)
			(layers "F.Cu" "F.Mask" "F.Paste")
			(net "M_M_DQ<19>")
		)
		(pad "DN72" smd circle
			(at 25.231598 18.664428)
			(size 0.4318 0.4318)
			(layers "F.Cu" "F.Mask" "F.Paste")
			(net "GND")
		)
		(pad "DN74" smd circle
			(at 26.948384 18.664428)
			(size 0.4318 0.4318)
			(layers "F.Cu" "F.Mask" "F.Paste")
			(net "M_K_DQ<30>")
		)
		(pad "DN76" smd circle
			(at 28.665424 18.664428)
			(size 0.4318 0.4318)
			(layers "F.Cu" "F.Mask" "F.Paste")
			(net "M_K_DQ<24>")
		)
		(pad "DN78" smd circle
			(at 30.382464 18.664428)
			(size 0.4318 0.4318)
			(layers "F.Cu" "F.Mask" "F.Paste")
			(net "GND")
		)
		(pad "DN80" smd circle
			(at 32.099504 18.664428)
			(size 0.4318 0.4318)
			(layers "F.Cu" "F.Mask" "F.Paste")
			(net "M_K_DQS_DN<11>")
		)
		(pad "DN82" smd circle
			(at 33.816544 18.664428)
			(size 0.4318 0.4318)
			(layers "F.Cu" "F.Mask" "F.Paste")
			(net "M_K_DQ<23>")
		)
		(pad "DN84" smd circle
			(at 35.533584 18.664428)
			(size 0.4318 0.4318)
			(layers "F.Cu" "F.Mask" "F.Paste")
			(net "M_K_DQS_DN<1>")
		)
		(pad "DP3" smd circle
			(at -35.533584 20.959572)
			(size 0.4318 0.4318)
			(layers "F.Cu" "F.Mask" "F.Paste")
			(net "TP_P3E_CPU1_PE1_MP_TXP<7>")
		)
		(pad "DP5" smd circle
			(at -33.816544 20.959572)
			(size 0.4318 0.4318)
			(layers "F.Cu" "F.Mask" "F.Paste")
			(net "P3E_CPU1_PE3_MP_TXN<9>")
		)
		(pad "DP7" smd circle
			(at -32.099504 20.959572)
			(size 0.4318 0.4318)
			(layers "F.Cu" "F.Mask" "F.Paste")
			(net "P3E_CPU1_PE3_MP_TXP<7>")
		)
		(pad "DP9" smd circle
			(at -30.382464 20.959572)
			(size 0.4318 0.4318)
			(layers "F.Cu" "F.Mask" "F.Paste")
			(net "GND")
		)
		(pad "DP11" smd circle
			(at -28.665424 20.959572)
			(size 0.4318 0.4318)
			(layers "F.Cu" "F.Mask" "F.Paste")
			(net "TP_P3E_CPU1_PE1_RSR3_RXN<9>")
		)
		(pad "DP13" smd circle
			(at -26.948384 20.959572)
			(size 0.4318 0.4318)
			(layers "F.Cu" "F.Mask" "F.Paste")
			(net "TP_P3E_CPU1_PE1_RSR3_RXP<11>")
		)
		(pad "DP15" smd circle
			(at -25.231598 20.959572)
			(size 0.4318 0.4318)
			(layers "F.Cu" "F.Mask" "F.Paste")
			(net "P3E_CPU1_PE3_MP_RXP<5>")
		)
		(pad "DP17" smd circle
			(at -23.514558 20.959572)
			(size 0.4318 0.4318)
			(layers "F.Cu" "F.Mask" "F.Paste")
			(net "TP_CPU1_RSVD_30")
		)
		(pad "DP19" smd circle
			(at -21.797518 20.959572)
			(size 0.4318 0.4318)
			(layers "F.Cu" "F.Mask" "F.Paste")
			(net "PVCCIO_CPU1")
		)
		(pad "DP21" smd circle
			(at -20.080478 20.959572)
			(size 0.4318 0.4318)
			(layers "F.Cu" "F.Mask" "F.Paste")
			(net "TP_CPU1_UPI2_RSVD_CA12")
		)
		(pad "DP23" smd circle
			(at -18.363438 20.959572)
			(size 0.4318 0.4318)
			(layers "F.Cu" "F.Mask" "F.Paste")
			(net "M_K_DQS_DP<16>")
		)
		(pad "DP25" smd circle
			(at -16.646398 20.959572)
			(size 0.4318 0.4318)
			(layers "F.Cu" "F.Mask" "F.Paste")
			(net "M_K_DQ<60>")
		)
		(pad "DP27" smd circle
			(at -14.929612 20.959572)
			(size 0.4318 0.4318)
			(layers "F.Cu" "F.Mask" "F.Paste")
			(net "M_K_DQ<50>")
		)
		(pad "DP29" smd circle
			(at -13.212572 20.959572)
			(size 0.4318 0.4318)
			(layers "F.Cu" "F.Mask" "F.Paste")
			(net "M_K_DQS_DP<15>")
		)
		(pad "DP31" smd circle
			(at -11.495532 20.959572)
			(size 0.4318 0.4318)
			(layers "F.Cu" "F.Mask" "F.Paste")
			(net "M_K_DQ<52>")
		)
		(pad "DP33" smd circle
			(at -9.778492 20.959572)
			(size 0.4318 0.4318)
			(layers "F.Cu" "F.Mask" "F.Paste")
			(net "M_K_DQ<42>")
		)
		(pad "DP35" smd circle
			(at -8.061452 20.959572)
			(size 0.4318 0.4318)
			(layers "F.Cu" "F.Mask" "F.Paste")
			(net "M_K_DQS_DN<14>")
		)
		(pad "DP37" smd circle
			(at -6.344412 20.959572)
			(size 0.4318 0.4318)
			(layers "F.Cu" "F.Mask" "F.Paste")
			(net "M_K_DQ<44>")
		)
		(pad "DP39" smd circle
			(at -4.627626 20.959572)
			(size 0.4318 0.4318)
			(layers "F.Cu" "F.Mask" "F.Paste")
			(net "M_L_DQ<34>")
		)
		(pad "DP41" smd circle
			(at -2.910586 20.959572)
			(size 0.4318 0.4318)
			(layers "F.Cu" "F.Mask" "F.Paste")
			(net "M_L_DQS_DN<13>")
		)
		(pad "DP45" smd circle
			(at 2.052066 19.159474)
			(size 0.4318 0.4318)
			(layers "F.Cu" "F.Mask" "F.Paste")
			(net "GND")
		)
		(pad "DP47" smd circle
			(at 3.769106 19.159474)
			(size 0.4318 0.4318)
			(layers "F.Cu" "F.Mask" "F.Paste")
			(net "GND")
		)
		(pad "DP49" smd circle
			(at 5.485892 19.159474)
			(size 0.4318 0.4318)
			(layers "F.Cu" "F.Mask" "F.Paste")
			(net "GND")
		)
		(pad "DP51" smd circle
			(at 7.202932 19.159474)
			(size 0.4318 0.4318)
			(layers "F.Cu" "F.Mask" "F.Paste")
			(net "GND")
		)
		(pad "DP53" smd circle
			(at 8.919972 19.159474)
			(size 0.4318 0.4318)
			(layers "F.Cu" "F.Mask" "F.Paste")
			(net "GND")
		)
		(pad "DP55" smd circle
			(at 10.637012 19.159474)
			(size 0.4318 0.4318)
			(layers "F.Cu" "F.Mask" "F.Paste")
			(net "GND")
		)
		(pad "DP57" smd circle
			(at 12.354052 19.159474)
			(size 0.4318 0.4318)
			(layers "F.Cu" "F.Mask" "F.Paste")
			(net "GND")
		)
		(pad "DP59" smd circle
			(at 14.071092 19.159474)
			(size 0.4318 0.4318)
			(layers "F.Cu" "F.Mask" "F.Paste")
			(net "GND")
		)
		(pad "DP61" smd circle
			(at 15.787878 19.159474)
			(size 0.4318 0.4318)
			(layers "F.Cu" "F.Mask" "F.Paste")
			(net "GND")
		)
		(pad "DP63" smd circle
			(at 17.504918 19.159474)
			(size 0.4318 0.4318)
			(layers "F.Cu" "F.Mask" "F.Paste")
			(net "GND")
		)
		(pad "DP65" smd circle
			(at 19.221958 19.159474)
			(size 0.4318 0.4318)
			(layers "F.Cu" "F.Mask" "F.Paste")
			(net "TP_CPU1_RSVD_29")
		)
		(pad "DP67" smd circle
			(at 20.938998 19.159474)
			(size 0.4318 0.4318)
			(layers "F.Cu" "F.Mask" "F.Paste")
			(net "GND")
		)
		(pad "DP69" smd circle
			(at 22.656038 19.159474)
			(size 0.4318 0.4318)
			(layers "F.Cu" "F.Mask" "F.Paste")
			(net "GND")
		)
		(pad "DP71" smd circle
			(at 24.373078 19.159474)
			(size 0.4318 0.4318)
			(layers "F.Cu" "F.Mask" "F.Paste")
			(net "GND")
		)
	)
)
